(kicad_pcb
	(version 20260206)
	(generator "pcbnew")
	(generator_version "10.0")
	(general
		(thickness 1.6)
		(legacy_teardrops no)
	)
	(paper "A4")
	(title_block
		(title "panther-plus-userver — 13130-1b_20150205.brd")
		(comment 1 "Honey Badger (Wiwynn) / footprints 50-57 of 1509")
	)
	(layers
		(0 "F.Cu" signal "TOP")
		(4 "In1.Cu" signal "L2")
		(6 "In2.Cu" signal "L3")
		(8 "In3.Cu" signal "L4")
		(10 "In4.Cu" signal "L5")
		(12 "In5.Cu" signal "L6")
		(14 "In6.Cu" signal "L7")
		(16 "In7.Cu" signal "L8")
		(18 "In8.Cu" signal "L9")
		(20 "In9.Cu" signal "L10")
		(22 "In10.Cu" signal "L11")
		(2 "B.Cu" signal "BOTTOM")
		(9 "F.Adhes" user "F.Adhesive")
		(11 "B.Adhes" user "B.Adhesive")
		(13 "F.Paste" user "Package Geometry/Pastemask Top")
		(15 "B.Paste" user "Package Geometry/Pastemask Bottom")
		(5 "F.SilkS" user "Ref Des/Silkscreen Top")
		(7 "B.SilkS" user "Ref Des/Silkscreen Bottom")
		(1 "F.Mask" user "Board Geometry/Soldermask Top")
		(3 "B.Mask" user "Board Geometry/Soldermask Bottom")
		(17 "Dwgs.User" user "User.Drawings")
		(19 "Cmts.User" user "User.Comments")
		(21 "Eco1.User" user "User.Eco1")
		(23 "Eco2.User" user "User.Eco2")
		(25 "Edge.Cuts" user "Board Geometry/Outline")
		(27 "Margin" user)
		(31 "F.CrtYd" user "Package Geometry/Place Bound Top")
		(29 "B.CrtYd" user "Package Geometry/Place Bound Bottom")
		(35 "F.Fab" user "Ref Des/Assembly Top")
		(33 "B.Fab" user "Ref Des/Assembly Bottom")
	)
	(footprint ""
		(layer "F.Cu")
		(at 194.183 -38.735 180)
		(property "Reference" "PC93"
			(at 0 0 180)
			(layer "F.SilkS")
			(hide yes)
			(effects
				(font
					(size 1.27 1.27)
				)
			)
		)
		(property "Value" "SC1U16V3KX-5GP"
			(at -0.0254 -2.0193 180)
			(unlocked yes)
			(layer "F.Fab")
			(hide yes)
			(effects
				(font
					(size 1.016 1.016)
					(thickness 0.1524)
				)
			)
		)
		(property "Device Type" "C603H36"
			(at -0.0254 -3.5433 180)
			(unlocked yes)
			(layer "F.Fab")
			(hide yes)
			(effects
				(font
					(size 1.016 1.016)
					(thickness 0.1524)
				)
			)
		)
		(duplicate_pad_numbers_are_jumpers no)
		(fp_line
			(start -0.4064 0)
			(end 0.4064 0)
			(stroke
				(width 0.2286)
				(type default)
			)
			(layer "F.SilkS")
		)
		(fp_rect
			(start -0.635 1.1811)
			(end 0.635 -1.1811)
			(stroke
				(width 0)
				(type default)
			)
			(fill no)
			(layer "F.CrtYd")
		)
		(fp_rect
			(start -0.635 1.1811)
			(end 0.635 -1.1811)
			(stroke
				(width 0)
				(type default)
			)
			(fill no)
			(layer "F.Fab")
		)
		(pad "1" smd custom
			(at 0 -0.6604 180)
			(size 0.19685 0.19685)
			(layers "F.Cu" "F.Mask" "F.Paste")
			(net "VR_PVDDR_A_VDDP")
			(options
				(clearance outline)
				(anchor circle)
			)
			(primitives
				(gr_poly
					(pts
						(arc
							(start 0.508 -0.2921)
							(mid 0.478242 -0.363942)
							(end 0.4064 -0.3937)
						)
						(arc
							(start -0.4064 -0.3937)
							(mid -0.478242 -0.363942)
							(end -0.508 -0.2921)
						)
						(arc
							(start -0.508 0.2921)
							(mid -0.478242 0.363942)
							(end -0.4064 0.3937)
						)
						(arc
							(start 0.4064 0.3937)
							(mid 0.478242 0.363942)
							(end 0.508 0.2921)
						)
					)
					(width 0)
					(fill yes)
				)
			)
		)
		(pad "2" smd custom
			(at 0 0.6604 180)
			(size 0.19685 0.19685)
			(layers "F.Cu" "F.Mask" "F.Paste")
			(net "GND")
			(options
				(clearance outline)
				(anchor circle)
			)
			(primitives
				(gr_poly
					(pts
						(arc
							(start 0.508 -0.2921)
							(mid 0.478242 -0.363942)
							(end 0.4064 -0.3937)
						)
						(arc
							(start -0.4064 -0.3937)
							(mid -0.478242 -0.363942)
							(end -0.508 -0.2921)
						)
						(arc
							(start -0.508 0.2921)
							(mid -0.478242 0.363942)
							(end -0.4064 0.3937)
						)
						(arc
							(start 0.4064 0.3937)
							(mid 0.478242 0.363942)
							(end 0.508 0.2921)
						)
					)
					(width 0)
					(fill yes)
				)
			)
		)
	)
	(footprint ""
		(layer "F.Cu")
		(at 183.261 -21.59 -90)
		(property "Reference" "PC41"
			(at 0 0 270)
			(layer "F.SilkS")
			(hide yes)
			(effects
				(font
					(size 1.27 1.27)
				)
			)
		)
		(property "Value" "SC4D7U10V3KX-GP"
			(at 0 -2.8194 270)
			(unlocked yes)
			(layer "F.Fab")
			(hide yes)
			(effects
				(font
					(size 1.016 1.016)
					(thickness 0.1524)
				)
			)
		)
		(property "Device Type" "C603H36"
			(at 0 -4.3434 270)
			(unlocked yes)
			(layer "F.Fab")
			(hide yes)
			(effects
				(font
					(size 1.016 1.016)
					(thickness 0.1524)
				)
			)
		)
		(duplicate_pad_numbers_are_jumpers no)
		(fp_line
			(start -0.4064 0)
			(end 0.4064 0)
			(stroke
				(width 0.2286)
				(type default)
			)
			(layer "F.SilkS")
		)
		(fp_rect
			(start -0.635 1.1811)
			(end 0.635 -1.1811)
			(stroke
				(width 0)
				(type default)
			)
			(fill no)
			(layer "F.CrtYd")
		)
		(fp_rect
			(start -0.635 1.1811)
			(end 0.635 -1.1811)
			(stroke
				(width 0)
				(type default)
			)
			(fill no)
			(layer "F.Fab")
		)
		(pad "1" smd custom
			(at 0 -0.6604 270)
			(size 0.19685 0.19685)
			(layers "F.Cu" "F.Mask" "F.Paste")
			(net "PV_VTT_DDR_B_VIN")
			(options
				(clearance outline)
				(anchor circle)
			)
			(primitives
				(gr_poly
					(pts
						(arc
							(start 0.508 -0.2921)
							(mid 0.478242 -0.363942)
							(end 0.4064 -0.3937)
						)
						(arc
							(start -0.4064 -0.3937)
							(mid -0.478242 -0.363942)
							(end -0.508 -0.2921)
						)
						(arc
							(start -0.508 0.2921)
							(mid -0.478242 0.363942)
							(end -0.4064 0.3937)
						)
						(arc
							(start 0.4064 0.3937)
							(mid 0.478242 0.363942)
							(end 0.508 0.2921)
						)
					)
					(width 0)
					(fill yes)
				)
			)
		)
		(pad "2" smd custom
			(at 0 0.6604 270)
			(size 0.19685 0.19685)
			(layers "F.Cu" "F.Mask" "F.Paste")
			(net "GND")
			(options
				(clearance outline)
				(anchor circle)
			)
			(primitives
				(gr_poly
					(pts
						(arc
							(start 0.508 -0.2921)
							(mid 0.478242 -0.363942)
							(end 0.4064 -0.3937)
						)
						(arc
							(start -0.4064 -0.3937)
							(mid -0.478242 -0.363942)
							(end -0.508 -0.2921)
						)
						(arc
							(start -0.508 0.2921)
							(mid -0.478242 0.363942)
							(end -0.4064 0.3937)
						)
						(arc
							(start 0.4064 0.3937)
							(mid 0.478242 0.363942)
							(end 0.508 0.2921)
						)
					)
					(width 0)
					(fill yes)
				)
			)
		)
	)
	(footprint ""
		(layer "F.Cu")
		(at 34.417 -38.7858 180)
		(property "Reference" "R271"
			(at 0 0 180)
			(layer "F.SilkS")
			(hide yes)
			(effects
				(font
					(size 1.27 1.27)
				)
			)
		)
		(property "Value" "0R3J-0-U-GP"
			(at -0.0254 -2.5146 180)
			(unlocked yes)
			(layer "F.Fab")
			(hide yes)
			(effects
				(font
					(size 1.016 1.016)
					(thickness 0.1524)
				)
			)
		)
		(property "Device Type" "R603H22"
			(at -0.0254 -4.0386 180)
			(unlocked yes)
			(layer "F.Fab")
			(hide yes)
			(effects
				(font
					(size 1.016 1.016)
					(thickness 0.1524)
				)
			)
		)
		(duplicate_pad_numbers_are_jumpers no)
		(fp_line
			(start 0.4318 0)
			(end 0.2032 0)
			(stroke
				(width 0.2032)
				(type default)
			)
			(layer "F.SilkS")
		)
		(fp_line
			(start -0.2032 0)
			(end -0.4191 0)
			(stroke
				(width 0.2032)
				(type default)
			)
			(layer "F.SilkS")
		)
		(fp_rect
			(start -0.635 1.1811)
			(end 0.635 -1.1811)
			(stroke
				(width 0)
				(type default)
			)
			(fill no)
			(layer "F.CrtYd")
		)
		(fp_rect
			(start -0.635 1.1811)
			(end 0.635 -1.1811)
			(stroke
				(width 0)
				(type default)
			)
			(fill no)
			(layer "F.Fab")
		)
		(pad "1" smd custom
			(at 0 -0.6604 180)
			(size 0.19685 0.19685)
			(layers "F.Cu" "F.Mask" "F.Paste")
			(net "XDP_P60")
			(options
				(clearance outline)
				(anchor circle)
			)
			(primitives
				(gr_poly
					(pts
						(arc
							(start 0.508 -0.2921)
							(mid 0.478242 -0.363942)
							(end 0.4064 -0.3937)
						)
						(arc
							(start -0.4064 -0.3937)
							(mid -0.478242 -0.363942)
							(end -0.508 -0.2921)
						)
						(arc
							(start -0.508 0.2921)
							(mid -0.478242 0.363942)
							(end -0.4064 0.3937)
						)
						(arc
							(start 0.4064 0.3937)
							(mid 0.478242 0.363942)
							(end 0.508 0.2921)
						)
					)
					(width 0)
					(fill yes)
				)
			)
		)
		(pad "2" smd custom
			(at 0 0.6604 180)
			(size 0.19685 0.19685)
			(layers "F.Cu" "F.Mask" "F.Paste")
			(net "GND")
			(options
				(clearance outline)
				(anchor circle)
			)
			(primitives
				(gr_poly
					(pts
						(arc
							(start 0.508 -0.2921)
							(mid 0.478242 -0.363942)
							(end 0.4064 -0.3937)
						)
						(arc
							(start -0.4064 -0.3937)
							(mid -0.478242 -0.363942)
							(end -0.508 -0.2921)
						)
						(arc
							(start -0.508 0.2921)
							(mid -0.478242 0.363942)
							(end -0.4064 0.3937)
						)
						(arc
							(start 0.4064 0.3937)
							(mid 0.478242 0.363942)
							(end 0.508 0.2921)
						)
					)
					(width 0)
					(fill yes)
				)
			)
		)
	)
	(footprint ""
		(layer "F.Cu")
		(at 23.98268 -64.8716 180)
		(property "Reference" "PC13"
			(at 0 0 180)
			(layer "F.SilkS")
			(hide yes)
			(effects
				(font
					(size 1.27 1.27)
				)
			)
		)
		(property "Value" "SCD22U16V3KX-2-GP"
			(at -0.0254 -2.0193 180)
			(unlocked yes)
			(layer "F.Fab")
			(hide yes)
			(effects
				(font
					(size 1.016 1.016)
					(thickness 0.1524)
				)
			)
		)
		(property "Device Type" "C603H36"
			(at -0.0254 -3.5433 180)
			(unlocked yes)
			(layer "F.Fab")
			(hide yes)
			(effects
				(font
					(size 1.016 1.016)
					(thickness 0.1524)
				)
			)
		)
		(duplicate_pad_numbers_are_jumpers no)
		(fp_line
			(start -0.4064 0)
			(end 0.4064 0)
			(stroke
				(width 0.2286)
				(type default)
			)
			(layer "F.SilkS")
		)
		(fp_rect
			(start -0.635 1.1811)
			(end 0.635 -1.1811)
			(stroke
				(width 0)
				(type default)
			)
			(fill no)
			(layer "F.CrtYd")
		)
		(fp_rect
			(start -0.635 1.1811)
			(end 0.635 -1.1811)
			(stroke
				(width 0)
				(type default)
			)
			(fill no)
			(layer "F.Fab")
		)
		(pad "1" smd custom
			(at 0 -0.6604 180)
			(size 0.19685 0.19685)
			(layers "F.Cu" "F.Mask" "F.Paste")
			(net "VR_PVNN_BOOT")
			(options
				(clearance outline)
				(anchor circle)
			)
			(primitives
				(gr_poly
					(pts
						(arc
							(start 0.508 -0.2921)
							(mid 0.478242 -0.363942)
							(end 0.4064 -0.3937)
						)
						(arc
							(start -0.4064 -0.3937)
							(mid -0.478242 -0.363942)
							(end -0.508 -0.2921)
						)
						(arc
							(start -0.508 0.2921)
							(mid -0.478242 0.363942)
							(end -0.4064 0.3937)
						)
						(arc
							(start 0.4064 0.3937)
							(mid 0.478242 0.363942)
							(end 0.508 0.2921)
						)
					)
					(width 0)
					(fill yes)
				)
			)
		)
		(pad "2" smd custom
			(at 0 0.6604 180)
			(size 0.19685 0.19685)
			(layers "F.Cu" "F.Mask" "F.Paste")
			(net "VR_PVNN_BOOT_R")
			(options
				(clearance outline)
				(anchor circle)
			)
			(primitives
				(gr_poly
					(pts
						(arc
							(start 0.508 -0.2921)
							(mid 0.478242 -0.363942)
							(end 0.4064 -0.3937)
						)
						(arc
							(start -0.4064 -0.3937)
							(mid -0.478242 -0.363942)
							(end -0.508 -0.2921)
						)
						(arc
							(start -0.508 0.2921)
							(mid -0.478242 0.363942)
							(end -0.4064 0.3937)
						)
						(arc
							(start 0.4064 0.3937)
							(mid 0.478242 0.363942)
							(end 0.508 0.2921)
						)
					)
					(width 0)
					(fill yes)
				)
			)
		)
	)
	(footprint ""
		(layer "F.Cu")
		(at 25.019 -49.276 180)
		(property "Reference" "PC54"
			(at 0 0 180)
			(layer "F.SilkS")
			(hide yes)
			(effects
				(font
					(size 1.27 1.27)
				)
			)
		)
		(property "Value" "SCD1U16V2KX-3GP"
			(at 1.8923 -1.2065 180)
			(unlocked yes)
			(layer "F.Fab")
			(hide yes)
			(effects
				(font
					(size 1.016 1.016)
					(thickness 0.1524)
				)
			)
		)
		(property "Device Type" "C402H22"
			(at 1.8923 -2.7305 180)
			(unlocked yes)
			(layer "F.Fab")
			(hide yes)
			(effects
				(font
					(size 1.016 1.016)
					(thickness 0.1524)
				)
			)
		)
		(duplicate_pad_numbers_are_jumpers no)
		(fp_rect
			(start -0.381 0.7366)
			(end 0.381 -0.7366)
			(stroke
				(width 0)
				(type default)
			)
			(fill no)
			(layer "F.CrtYd")
		)
		(fp_rect
			(start -0.381 0.7366)
			(end 0.381 -0.7366)
			(stroke
				(width 0)
				(type default)
			)
			(fill no)
			(layer "F.Fab")
		)
		(pad "1" smd custom
			(at 0 -0.4572 180)
			(size 0.1143 0.1143)
			(layers "F.Cu" "F.Mask" "F.Paste")
			(net "VR_PVCCP_ISUMN")
			(options
				(clearance outline)
				(anchor circle)
			)
			(primitives
				(gr_poly
					(pts
						(arc
							(start -0.254 -0.1778)
							(mid -0.239121 -0.213721)
							(end -0.2032 -0.2286)
						)
						(arc
							(start 0.2032 -0.2286)
							(mid 0.239121 -0.213721)
							(end 0.254 -0.1778)
						)
						(arc
							(start 0.254 0.1778)
							(mid 0.239121 0.213721)
							(end 0.2032 0.2286)
						)
						(arc
							(start -0.2032 0.2286)
							(mid -0.239121 0.213721)
							(end -0.254 0.1778)
						)
					)
					(width 0)
					(fill yes)
				)
			)
		)
		(pad "2" smd custom
			(at 0 0.4572 180)
			(size 0.1143 0.1143)
			(layers "F.Cu" "F.Mask" "F.Paste")
			(net "GND")
			(options
				(clearance outline)
				(anchor circle)
			)
			(primitives
				(gr_poly
					(pts
						(arc
							(start -0.254 -0.1778)
							(mid -0.239121 -0.213721)
							(end -0.2032 -0.2286)
						)
						(arc
							(start 0.2032 -0.2286)
							(mid 0.239121 -0.213721)
							(end 0.254 -0.1778)
						)
						(arc
							(start 0.254 0.1778)
							(mid 0.239121 0.213721)
							(end 0.2032 0.2286)
						)
						(arc
							(start -0.2032 0.2286)
							(mid -0.239121 0.213721)
							(end -0.254 0.1778)
						)
					)
					(width 0)
					(fill yes)
				)
			)
		)
	)
	(footprint ""
		(layer "F.Cu")
		(at 63.627 -13.589)
		(property "Reference" "C308"
			(at 0 0 0)
			(layer "F.SilkS")
			(hide yes)
			(effects
				(font
					(size 1.27 1.27)
				)
			)
		)
		(property "Value" "SCD01U16V2KX-3GP"
			(at 1.8923 -1.2065 0)
			(unlocked yes)
			(layer "F.Fab")
			(hide yes)
			(effects
				(font
					(size 1.016 1.016)
					(thickness 0.1524)
				)
			)
		)
		(property "Device Type" "C402H22"
			(at 1.8923 -2.7305 0)
			(unlocked yes)
			(layer "F.Fab")
			(hide yes)
			(effects
				(font
					(size 1.016 1.016)
					(thickness 0.1524)
				)
			)
		)
		(duplicate_pad_numbers_are_jumpers no)
		(fp_rect
			(start -0.381 0.7366)
			(end 0.381 -0.7366)
			(stroke
				(width 0)
				(type default)
			)
			(fill no)
			(layer "F.CrtYd")
		)
		(fp_rect
			(start -0.381 0.7366)
			(end 0.381 -0.7366)
			(stroke
				(width 0)
				(type default)
			)
			(fill no)
			(layer "F.Fab")
		)
		(pad "1" smd custom
			(at 0 -0.4572)
			(size 0.1143 0.1143)
			(layers "F.Cu" "F.Mask" "F.Paste")
			(net "SATA2_RX_DN0")
			(options
				(clearance outline)
				(anchor circle)
			)
			(primitives
				(gr_poly
					(pts
						(arc
							(start -0.254 -0.1778)
							(mid -0.239121 -0.213721)
							(end -0.2032 -0.2286)
						)
						(arc
							(start 0.2032 -0.2286)
							(mid 0.239121 -0.213721)
							(end 0.254 -0.1778)
						)
						(arc
							(start 0.254 0.1778)
							(mid 0.239121 0.213721)
							(end 0.2032 0.2286)
						)
						(arc
							(start -0.2032 0.2286)
							(mid -0.239121 0.213721)
							(end -0.254 0.1778)
						)
					)
					(width 0)
					(fill yes)
				)
			)
		)
		(pad "2" smd custom
			(at 0 0.4572)
			(size 0.1143 0.1143)
			(layers "F.Cu" "F.Mask" "F.Paste")
			(net "SATA2_RX_C_DN0")
			(options
				(clearance outline)
				(anchor circle)
			)
			(primitives
				(gr_poly
					(pts
						(arc
							(start -0.254 -0.1778)
							(mid -0.239121 -0.213721)
							(end -0.2032 -0.2286)
						)
						(arc
							(start 0.2032 -0.2286)
							(mid 0.239121 -0.213721)
							(end 0.254 -0.1778)
						)
						(arc
							(start 0.254 0.1778)
							(mid 0.239121 0.213721)
							(end 0.2032 0.2286)
						)
						(arc
							(start -0.2032 0.2286)
							(mid -0.239121 0.213721)
							(end -0.254 0.1778)
						)
					)
					(width 0)
					(fill yes)
				)
			)
		)
	)
	(footprint ""
		(layer "F.Cu")
		(at 109.2708 -20.193 90)
		(property "Reference" "R160"
			(at 0 0 90)
			(layer "F.SilkS")
			(hide yes)
			(effects
				(font
					(size 1.27 1.27)
				)
			)
		)
		(property "Value" "100R2F-L1-GP-U"
			(at 0.064008 -3.993896 90)
			(unlocked yes)
			(layer "F.Fab")
			(hide yes)
			(effects
				(font
					(size 1.016 1.016)
					(thickness 0.1524)
				)
			)
		)
		(property "Device Type" "R402H14"
			(at 0.064008 -5.517896 90)
			(unlocked yes)
			(layer "F.Fab")
			(hide yes)
			(effects
				(font
					(size 1.016 1.016)
					(thickness 0.1524)
				)
			)
		)
		(duplicate_pad_numbers_are_jumpers no)
		(fp_rect
			(start -0.381 0.8382)
			(end 0.381 -0.8382)
			(stroke
				(width 0)
				(type default)
			)
			(fill no)
			(layer "F.CrtYd")
		)
		(fp_rect
			(start -0.381 0.8382)
			(end 0.381 -0.8382)
			(stroke
				(width 0)
				(type default)
			)
			(fill no)
			(layer "F.Fab")
		)
		(pad "1" smd custom
			(at 0 -0.4318 90)
			(size 0.127 0.127)
			(layers "F.Cu" "F.Mask" "F.Paste")
			(net "M_B_MON2_P")
			(options
				(clearance outline)
				(anchor circle)
			)
			(primitives
				(gr_poly
					(pts
						(arc
							(start -0.2032 -0.2794)
							(mid -0.239121 -0.264521)
							(end -0.254 -0.2286)
						)
						(arc
							(start -0.254 0.2286)
							(mid -0.239121 0.264521)
							(end -0.2032 0.2794)
						)
						(arc
							(start 0.2032 0.2794)
							(mid 0.239121 0.264521)
							(end 0.254 0.2286)
						)
						(arc
							(start 0.254 -0.2286)
							(mid 0.239121 -0.264521)
							(end 0.2032 -0.2794)
						)
					)
					(width 0)
					(fill yes)
				)
			)
		)
		(pad "2" smd custom
			(at 0 0.4318 90)
			(size 0.127 0.127)
			(layers "F.Cu" "F.Mask" "F.Paste")
			(net "M_B_MON2_N")
			(options
				(clearance outline)
				(anchor circle)
			)
			(primitives
				(gr_poly
					(pts
						(arc
							(start -0.2032 -0.2794)
							(mid -0.239121 -0.264521)
							(end -0.254 -0.2286)
						)
						(arc
							(start -0.254 0.2286)
							(mid -0.239121 0.264521)
							(end -0.2032 0.2794)
						)
						(arc
							(start 0.2032 0.2794)
							(mid 0.239121 0.264521)
							(end 0.254 0.2286)
						)
						(arc
							(start 0.254 -0.2286)
							(mid 0.239121 -0.264521)
							(end 0.2032 -0.2794)
						)
					)
					(width 0)
					(fill yes)
				)
			)
		)
	)
	(footprint ""
		(layer "F.Cu")
		(at 13.716 -54.864)
		(property "Reference" "PR70"
			(at 0 0 0)
			(layer "F.SilkS")
			(hide yes)
			(effects
				(font
					(size 1.27 1.27)
				)
			)
		)
		(property "Value" "19K6R2D-GP"
			(at 1.7907 -1.1176 0)
			(unlocked yes)
			(layer "F.Fab")
			(hide yes)
			(effects
				(font
					(size 1.016 1.016)
					(thickness 0.1524)
				)
			)
		)
		(property "Device Type" "R402H16"
			(at 1.7907 -2.6416 0)
			(unlocked yes)
			(layer "F.Fab")
			(hide yes)
			(effects
				(font
					(size 1.016 1.016)
					(thickness 0.1524)
				)
			)
		)
		(duplicate_pad_numbers_are_jumpers no)
		(fp_rect
			(start -0.381 0.8382)
			(end 0.381 -0.8382)
			(stroke
				(width 0)
				(type default)
			)
			(fill no)
			(layer "F.CrtYd")
		)
		(fp_rect
			(start -0.381 0.8382)
			(end 0.381 -0.8382)
			(stroke
				(width 0)
				(type default)
			)
			(fill no)
			(layer "F.Fab")
		)
		(pad "1" smd custom
			(at 0 -0.4318)
			(size 0.127 0.127)
			(layers "F.Cu" "F.Mask" "F.Paste")
			(net "VR_PVCCP_IMON")
			(options
				(clearance outline)
				(anchor circle)
			)
			(primitives
				(gr_poly
					(pts
						(arc
							(start -0.2032 -0.2794)
							(mid -0.239121 -0.264521)
							(end -0.254 -0.2286)
						)
						(arc
							(start -0.254 0.2286)
							(mid -0.239121 0.264521)
							(end -0.2032 0.2794)
						)
						(arc
							(start 0.2032 0.2794)
							(mid 0.239121 0.264521)
							(end 0.254 0.2286)
						)
						(arc
							(start 0.254 -0.2286)
							(mid 0.239121 -0.264521)
							(end 0.2032 -0.2794)
						)
					)
					(width 0)
					(fill yes)
				)
			)
		)
		(pad "2" smd custom
			(at 0 0.4318)
			(size 0.127 0.127)
			(layers "F.Cu" "F.Mask" "F.Paste")
			(net "GND")
			(options
				(clearance outline)
				(anchor circle)
			)
			(primitives
				(gr_poly
					(pts
						(arc
							(start -0.2032 -0.2794)
							(mid -0.239121 -0.264521)
							(end -0.254 -0.2286)
						)
						(arc
							(start -0.254 0.2286)
							(mid -0.239121 0.264521)
							(end -0.2032 0.2794)
						)
						(arc
							(start 0.2032 0.2794)
							(mid 0.239121 0.264521)
							(end 0.254 0.2286)
						)
						(arc
							(start 0.254 -0.2286)
							(mid 0.239121 -0.264521)
							(end 0.2032 -0.2794)
						)
					)
					(width 0)
					(fill yes)
				)
			)
		)
	)
)
